(kicad_pcb
	(version 20260206)
	(generator "pcbnew")
	(generator_version "10.0")
	(general
		(thickness 1.6)
		(legacy_teardrops no)
	)
	(paper "A4")
	(title_block
		(title "01162023_DA0F0TEBIF0_F0T_Expander_BD_F_brd_V02_OCP.brd")
		(comment 1 "Grand Teton / footprints 1916-1921 of 9728")
	)
	(layers
		(0 "F.Cu" signal "TOP")
		(4 "In1.Cu" signal "GND")
		(6 "In2.Cu" signal "VCC")
		(8 "In3.Cu" signal "VCC1")
		(10 "In4.Cu" signal "GND1")
		(12 "In5.Cu" signal "IN1")
		(14 "In6.Cu" signal "GND2")
		(16 "In7.Cu" signal "IN2")
		(18 "In8.Cu" signal "GND3")
		(20 "In9.Cu" signal "IN3")
		(22 "In10.Cu" signal "GND4")
		(24 "In11.Cu" signal "IN4")
		(26 "In12.Cu" signal "GND5")
		(28 "In13.Cu" signal "IN5")
		(30 "In14.Cu" signal "GND6")
		(32 "In15.Cu" signal "IN6")
		(34 "In16.Cu" signal "GND7")
		(2 "B.Cu" signal "BOTTOM")
		(9 "F.Adhes" user "F.Adhesive")
		(11 "B.Adhes" user "B.Adhesive")
		(13 "F.Paste" user "Package Geometry/Pastemask Top")
		(15 "B.Paste" user "Package Geometry/Pastemask Bottom")
		(5 "F.SilkS" user "Ref Des/Silkscreen Top")
		(7 "B.SilkS" user "Ref Des/Silkscreen Bottom")
		(1 "F.Mask" user "Board Geometry/Soldermask Top")
		(3 "B.Mask" user "Board Geometry/Soldermask Bottom")
		(17 "Dwgs.User" user "User.Drawings")
		(19 "Cmts.User" user "User.Comments")
		(21 "Eco1.User" user "User.Eco1")
		(23 "Eco2.User" user "User.Eco2")
		(25 "Edge.Cuts" user "Board Geometry/Outline")
		(27 "Margin" user)
		(31 "F.CrtYd" user "Package Geometry/Place Bound Top")
		(29 "B.CrtYd" user "Package Geometry/Place Bound Bottom")
		(35 "F.Fab" user "Ref Des/Assembly Top")
		(33 "B.Fab" user "Ref Des/Assembly Bottom")
	)
	(footprint ""
		(layer "F.Cu")
		(at 242.777264 -119.105426 90)
		(property "Reference" "R6034"
			(at 0 0 90)
			(layer "F.SilkS")
			(hide yes)
			(effects
				(font
					(size 1.27 1.27)
				)
			)
		)
		(property "Value" ""
			(at 0 0 90)
			(layer "F.Fab")
			(effects
				(font
					(size 1.27 1.27)
				)
			)
		)
		(duplicate_pad_numbers_are_jumpers no)
		(fp_line
			(start 0.7874 -0.4064)
			(end 0.7874 0.4064)
			(stroke
				(width 0.1524)
				(type default)
			)
			(layer "F.SilkS")
		)
		(fp_line
			(start -0.7874 -0.4064)
			(end 0.7874 -0.4064)
			(stroke
				(width 0.1524)
				(type default)
			)
			(layer "F.SilkS")
		)
		(fp_line
			(start 0.7874 0.4064)
			(end -0.7874 0.4064)
			(stroke
				(width 0.1524)
				(type default)
			)
			(layer "F.SilkS")
		)
		(fp_line
			(start -0.7874 0.4064)
			(end -0.7874 -0.4064)
			(stroke
				(width 0.1524)
				(type default)
			)
			(layer "F.SilkS")
		)
		(fp_line
			(start -0.12065 -0.305054)
			(end -0.12065 -0.2794)
			(stroke
				(width 0.1)
				(type default)
			)
			(layer "F.Fab")
		)
		(fp_line
			(start -0.67945 -0.305054)
			(end -0.12065 -0.305054)
			(stroke
				(width 0.1)
				(type default)
			)
			(layer "F.Fab")
		)
		(fp_line
			(start 0.67945 -0.3048)
			(end 0.67945 0.3048)
			(stroke
				(width 0.1)
				(type default)
			)
			(layer "F.Fab")
		)
		(fp_line
			(start 0.12065 -0.3048)
			(end 0.67945 -0.3048)
			(stroke
				(width 0.1)
				(type default)
			)
			(layer "F.Fab")
		)
		(fp_line
			(start 0.12065 -0.2794)
			(end 0.12065 -0.3048)
			(stroke
				(width 0.1)
				(type default)
			)
			(layer "F.Fab")
		)
		(fp_line
			(start -0.12065 -0.2794)
			(end 0.12065 -0.2794)
			(stroke
				(width 0.1)
				(type default)
			)
			(layer "F.Fab")
		)
		(fp_line
			(start 0.120396 0.2794)
			(end -0.12065 0.2794)
			(stroke
				(width 0.1)
				(type default)
			)
			(layer "F.Fab")
		)
		(fp_line
			(start -0.12065 0.2794)
			(end -0.12065 0.3048)
			(stroke
				(width 0.1)
				(type default)
			)
			(layer "F.Fab")
		)
		(fp_line
			(start 0.67945 0.3048)
			(end 0.120396 0.3048)
			(stroke
				(width 0.1)
				(type default)
			)
			(layer "F.Fab")
		)
		(fp_line
			(start 0.120396 0.3048)
			(end 0.120396 0.2794)
			(stroke
				(width 0.1)
				(type default)
			)
			(layer "F.Fab")
		)
		(fp_line
			(start -0.12065 0.3048)
			(end -0.67945 0.3048)
			(stroke
				(width 0.1)
				(type default)
			)
			(layer "F.Fab")
		)
		(fp_line
			(start -0.67945 0.3048)
			(end -0.67945 -0.305054)
			(stroke
				(width 0.1)
				(type default)
			)
			(layer "F.Fab")
		)
		(pad "1" smd circle
			(at -0.40005 0 90)
			(size 0 0)
			(layers "F.Cu" "F.Mask" "F.Paste")
			(net "PWRGD_P3V3_NIC4_D")
		)
		(pad "2" smd circle
			(at 0.40005 0 90)
			(size 0 0)
			(layers "F.Cu" "F.Mask" "F.Paste")
			(net "PWRGD_P3V3_NIC4_R")
		)
	)
	(footprint ""
		(layer "F.Cu")
		(at 229.16515 -258.375912 -90)
		(property "Reference" "R6502"
			(at 0 0 270)
			(layer "F.SilkS")
			(hide yes)
			(effects
				(font
					(size 1.27 1.27)
				)
			)
		)
		(property "Value" ""
			(at 0 0 270)
			(layer "F.Fab")
			(effects
				(font
					(size 1.27 1.27)
				)
			)
		)
		(duplicate_pad_numbers_are_jumpers no)
		(fp_line
			(start -0.7874 0.4064)
			(end -0.7874 -0.4064)
			(stroke
				(width 0.1524)
				(type default)
			)
			(layer "F.SilkS")
		)
		(fp_line
			(start 0.7874 0.4064)
			(end -0.7874 0.4064)
			(stroke
				(width 0.1524)
				(type default)
			)
			(layer "F.SilkS")
		)
		(fp_line
			(start -0.7874 -0.4064)
			(end 0.7874 -0.4064)
			(stroke
				(width 0.1524)
				(type default)
			)
			(layer "F.SilkS")
		)
		(fp_line
			(start 0.7874 -0.4064)
			(end 0.7874 0.4064)
			(stroke
				(width 0.1524)
				(type default)
			)
			(layer "F.SilkS")
		)
		(fp_line
			(start -0.67945 0.3048)
			(end -0.67945 -0.305054)
			(stroke
				(width 0.1)
				(type default)
			)
			(layer "F.Fab")
		)
		(fp_line
			(start -0.12065 0.3048)
			(end -0.67945 0.3048)
			(stroke
				(width 0.1)
				(type default)
			)
			(layer "F.Fab")
		)
		(fp_line
			(start 0.120396 0.3048)
			(end 0.120396 0.2794)
			(stroke
				(width 0.1)
				(type default)
			)
			(layer "F.Fab")
		)
		(fp_line
			(start 0.67945 0.3048)
			(end 0.120396 0.3048)
			(stroke
				(width 0.1)
				(type default)
			)
			(layer "F.Fab")
		)
		(fp_line
			(start -0.12065 0.2794)
			(end -0.12065 0.3048)
			(stroke
				(width 0.1)
				(type default)
			)
			(layer "F.Fab")
		)
		(fp_line
			(start 0.120396 0.2794)
			(end -0.12065 0.2794)
			(stroke
				(width 0.1)
				(type default)
			)
			(layer "F.Fab")
		)
		(fp_line
			(start -0.12065 -0.2794)
			(end 0.12065 -0.2794)
			(stroke
				(width 0.1)
				(type default)
			)
			(layer "F.Fab")
		)
		(fp_line
			(start 0.12065 -0.2794)
			(end 0.12065 -0.3048)
			(stroke
				(width 0.1)
				(type default)
			)
			(layer "F.Fab")
		)
		(fp_line
			(start 0.12065 -0.3048)
			(end 0.67945 -0.3048)
			(stroke
				(width 0.1)
				(type default)
			)
			(layer "F.Fab")
		)
		(fp_line
			(start 0.67945 -0.3048)
			(end 0.67945 0.3048)
			(stroke
				(width 0.1)
				(type default)
			)
			(layer "F.Fab")
		)
		(fp_line
			(start -0.67945 -0.305054)
			(end -0.12065 -0.305054)
			(stroke
				(width 0.1)
				(type default)
			)
			(layer "F.Fab")
		)
		(fp_line
			(start -0.12065 -0.305054)
			(end -0.12065 -0.2794)
			(stroke
				(width 0.1)
				(type default)
			)
			(layer "F.Fab")
		)
		(pad "1" smd circle
			(at -0.40005 0 270)
			(size 0 0)
			(layers "F.Cu" "F.Mask" "F.Paste")
			(net "P1V25_SERDES_VDDPLL_PEX1")
		)
		(pad "2" smd circle
			(at 0.40005 0 270)
			(size 0 0)
			(layers "F.Cu" "F.Mask" "F.Paste")
			(net "P1V25_SERDES_VDDPLL_PEX1_C9")
		)
	)
	(footprint ""
		(layer "F.Cu")
		(at 408.47899 -59.577986 -90)
		(property "Reference" "R899"
			(at 0 0 270)
			(layer "F.SilkS")
			(hide yes)
			(effects
				(font
					(size 1.27 1.27)
				)
			)
		)
		(property "Value" ""
			(at 0 0 270)
			(layer "F.Fab")
			(effects
				(font
					(size 1.27 1.27)
				)
			)
		)
		(duplicate_pad_numbers_are_jumpers no)
		(fp_line
			(start -0.7874 0.4064)
			(end -0.7874 -0.4064)
			(stroke
				(width 0.1524)
				(type default)
			)
			(layer "F.SilkS")
		)
		(fp_line
			(start 0.7874 0.4064)
			(end -0.7874 0.4064)
			(stroke
				(width 0.1524)
				(type default)
			)
			(layer "F.SilkS")
		)
		(fp_line
			(start -0.7874 -0.4064)
			(end 0.7874 -0.4064)
			(stroke
				(width 0.1524)
				(type default)
			)
			(layer "F.SilkS")
		)
		(fp_line
			(start 0.7874 -0.4064)
			(end 0.7874 0.4064)
			(stroke
				(width 0.1524)
				(type default)
			)
			(layer "F.SilkS")
		)
		(fp_line
			(start -0.67945 0.3048)
			(end -0.67945 -0.305054)
			(stroke
				(width 0.1)
				(type default)
			)
			(layer "F.Fab")
		)
		(fp_line
			(start -0.12065 0.3048)
			(end -0.67945 0.3048)
			(stroke
				(width 0.1)
				(type default)
			)
			(layer "F.Fab")
		)
		(fp_line
			(start 0.120396 0.3048)
			(end 0.120396 0.2794)
			(stroke
				(width 0.1)
				(type default)
			)
			(layer "F.Fab")
		)
		(fp_line
			(start 0.67945 0.3048)
			(end 0.120396 0.3048)
			(stroke
				(width 0.1)
				(type default)
			)
			(layer "F.Fab")
		)
		(fp_line
			(start -0.12065 0.2794)
			(end -0.12065 0.3048)
			(stroke
				(width 0.1)
				(type default)
			)
			(layer "F.Fab")
		)
		(fp_line
			(start 0.120396 0.2794)
			(end -0.12065 0.2794)
			(stroke
				(width 0.1)
				(type default)
			)
			(layer "F.Fab")
		)
		(fp_line
			(start -0.12065 -0.2794)
			(end 0.12065 -0.2794)
			(stroke
				(width 0.1)
				(type default)
			)
			(layer "F.Fab")
		)
		(fp_line
			(start 0.12065 -0.2794)
			(end 0.12065 -0.3048)
			(stroke
				(width 0.1)
				(type default)
			)
			(layer "F.Fab")
		)
		(fp_line
			(start 0.12065 -0.3048)
			(end 0.67945 -0.3048)
			(stroke
				(width 0.1)
				(type default)
			)
			(layer "F.Fab")
		)
		(fp_line
			(start 0.67945 -0.3048)
			(end 0.67945 0.3048)
			(stroke
				(width 0.1)
				(type default)
			)
			(layer "F.Fab")
		)
		(fp_line
			(start -0.67945 -0.305054)
			(end -0.12065 -0.305054)
			(stroke
				(width 0.1)
				(type default)
			)
			(layer "F.Fab")
		)
		(fp_line
			(start -0.12065 -0.305054)
			(end -0.12065 -0.2794)
			(stroke
				(width 0.1)
				(type default)
			)
			(layer "F.Fab")
		)
		(pad "1" smd circle
			(at -0.40005 0 270)
			(size 0 0)
			(layers "F.Cu" "F.Mask" "F.Paste")
			(net "P3V3_SSD14")
		)
		(pad "2" smd circle
			(at 0.40005 0 270)
			(size 0 0)
			(layers "F.Cu" "F.Mask" "F.Paste")
			(net "PWRGD_P3V3_SSD14")
		)
	)
	(footprint ""
		(layer "F.Cu")
		(at 225.915474 -136.669272 -90)
		(property "Reference" "R4217"
			(at 0 0 270)
			(layer "F.SilkS")
			(hide yes)
			(effects
				(font
					(size 1.27 1.27)
				)
			)
		)
		(property "Value" ""
			(at 0 0 270)
			(layer "F.Fab")
			(effects
				(font
					(size 1.27 1.27)
				)
			)
		)
		(duplicate_pad_numbers_are_jumpers no)
		(fp_line
			(start -0.7874 0.4064)
			(end -0.7874 -0.4064)
			(stroke
				(width 0.1524)
				(type default)
			)
			(layer "F.SilkS")
		)
		(fp_line
			(start 0.7874 0.4064)
			(end -0.7874 0.4064)
			(stroke
				(width 0.1524)
				(type default)
			)
			(layer "F.SilkS")
		)
		(fp_line
			(start -0.7874 -0.4064)
			(end 0.7874 -0.4064)
			(stroke
				(width 0.1524)
				(type default)
			)
			(layer "F.SilkS")
		)
		(fp_line
			(start 0.7874 -0.4064)
			(end 0.7874 0.4064)
			(stroke
				(width 0.1524)
				(type default)
			)
			(layer "F.SilkS")
		)
		(fp_line
			(start -0.67945 0.3048)
			(end -0.67945 -0.305054)
			(stroke
				(width 0.1)
				(type default)
			)
			(layer "F.Fab")
		)
		(fp_line
			(start -0.12065 0.3048)
			(end -0.67945 0.3048)
			(stroke
				(width 0.1)
				(type default)
			)
			(layer "F.Fab")
		)
		(fp_line
			(start 0.120396 0.3048)
			(end 0.120396 0.2794)
			(stroke
				(width 0.1)
				(type default)
			)
			(layer "F.Fab")
		)
		(fp_line
			(start 0.67945 0.3048)
			(end 0.120396 0.3048)
			(stroke
				(width 0.1)
				(type default)
			)
			(layer "F.Fab")
		)
		(fp_line
			(start -0.12065 0.2794)
			(end -0.12065 0.3048)
			(stroke
				(width 0.1)
				(type default)
			)
			(layer "F.Fab")
		)
		(fp_line
			(start 0.120396 0.2794)
			(end -0.12065 0.2794)
			(stroke
				(width 0.1)
				(type default)
			)
			(layer "F.Fab")
		)
		(fp_line
			(start -0.12065 -0.2794)
			(end 0.12065 -0.2794)
			(stroke
				(width 0.1)
				(type default)
			)
			(layer "F.Fab")
		)
		(fp_line
			(start 0.12065 -0.2794)
			(end 0.12065 -0.3048)
			(stroke
				(width 0.1)
				(type default)
			)
			(layer "F.Fab")
		)
		(fp_line
			(start 0.12065 -0.3048)
			(end 0.67945 -0.3048)
			(stroke
				(width 0.1)
				(type default)
			)
			(layer "F.Fab")
		)
		(fp_line
			(start 0.67945 -0.3048)
			(end 0.67945 0.3048)
			(stroke
				(width 0.1)
				(type default)
			)
			(layer "F.Fab")
		)
		(fp_line
			(start -0.67945 -0.305054)
			(end -0.12065 -0.305054)
			(stroke
				(width 0.1)
				(type default)
			)
			(layer "F.Fab")
		)
		(fp_line
			(start -0.12065 -0.305054)
			(end -0.12065 -0.2794)
			(stroke
				(width 0.1)
				(type default)
			)
			(layer "F.Fab")
		)
		(pad "1" smd circle
			(at -0.40005 0 270)
			(size 0 0)
			(layers "F.Cu" "F.Mask" "F.Paste")
			(net "SMB_CK440_PEX_CLK_SCL")
		)
		(pad "2" smd circle
			(at 0.40005 0 270)
			(size 0 0)
			(layers "F.Cu" "F.Mask" "F.Paste")
			(net "SMB_CLK_ISO_R_SCL")
		)
	)
	(footprint ""
		(layer "F.Cu")
		(at 72.174862 -48.753014 180)
		(property "Reference" "C3668"
			(at 0 0 180)
			(layer "F.SilkS")
			(hide yes)
			(effects
				(font
					(size 1.27 1.27)
				)
			)
		)
		(property "Value" ""
			(at 0 0 180)
			(layer "F.Fab")
			(effects
				(font
					(size 1.27 1.27)
				)
			)
		)
		(duplicate_pad_numbers_are_jumpers no)
		(fp_line
			(start 0.7874 0.4064)
			(end -0.7874 0.4064)
			(stroke
				(width 0.1524)
				(type default)
			)
			(layer "F.SilkS")
		)
		(fp_line
			(start 0.7874 -0.4064)
			(end 0.7874 0.4064)
			(stroke
				(width 0.1524)
				(type default)
			)
			(layer "F.SilkS")
		)
		(fp_line
			(start -0.7874 0.4064)
			(end -0.7874 -0.4064)
			(stroke
				(width 0.1524)
				(type default)
			)
			(layer "F.SilkS")
		)
		(fp_line
			(start -0.7874 -0.4064)
			(end 0.7874 -0.4064)
			(stroke
				(width 0.1524)
				(type default)
			)
			(layer "F.SilkS")
		)
		(fp_line
			(start 0.67945 0.3048)
			(end 0.120396 0.3048)
			(stroke
				(width 0.1)
				(type default)
			)
			(layer "F.Fab")
		)
		(fp_line
			(start 0.67945 -0.3048)
			(end 0.67945 0.3048)
			(stroke
				(width 0.1)
				(type default)
			)
			(layer "F.Fab")
		)
		(fp_line
			(start 0.12065 -0.2794)
			(end 0.12065 -0.3048)
			(stroke
				(width 0.1)
				(type default)
			)
			(layer "F.Fab")
		)
		(fp_line
			(start 0.12065 -0.3048)
			(end 0.67945 -0.3048)
			(stroke
				(width 0.1)
				(type default)
			)
			(layer "F.Fab")
		)
		(fp_line
			(start 0.120396 0.3048)
			(end 0.120396 0.2794)
			(stroke
				(width 0.1)
				(type default)
			)
			(layer "F.Fab")
		)
		(fp_line
			(start 0.120396 0.2794)
			(end -0.12065 0.2794)
			(stroke
				(width 0.1)
				(type default)
			)
			(layer "F.Fab")
		)
		(fp_line
			(start -0.12065 0.3048)
			(end -0.67945 0.3048)
			(stroke
				(width 0.1)
				(type default)
			)
			(layer "F.Fab")
		)
		(fp_line
			(start -0.12065 0.2794)
			(end -0.12065 0.3048)
			(stroke
				(width 0.1)
				(type default)
			)
			(layer "F.Fab")
		)
		(fp_line
			(start -0.12065 -0.2794)
			(end 0.12065 -0.2794)
			(stroke
				(width 0.1)
				(type default)
			)
			(layer "F.Fab")
		)
		(fp_line
			(start -0.12065 -0.305054)
			(end -0.12065 -0.2794)
			(stroke
				(width 0.1)
				(type default)
			)
			(layer "F.Fab")
		)
		(fp_line
			(start -0.67945 0.3048)
			(end -0.67945 -0.305054)
			(stroke
				(width 0.1)
				(type default)
			)
			(layer "F.Fab")
		)
		(fp_line
			(start -0.67945 -0.305054)
			(end -0.12065 -0.305054)
			(stroke
				(width 0.1)
				(type default)
			)
			(layer "F.Fab")
		)
		(pad "1" smd circle
			(at -0.40005 0 180)
			(size 0 0)
			(layers "F.Cu" "F.Mask" "F.Paste")
			(net "P3V3_AUX")
		)
		(pad "2" smd circle
			(at 0.40005 0 180)
			(size 0 0)
			(layers "F.Cu" "F.Mask" "F.Paste")
			(net "GND")
		)
	)
	(footprint ""
		(layer "F.Cu")
		(at 18.679922 -135.62711 90)
		(property "Reference" "PD6"
			(at -1.87071 2.403348 90)
			(unlocked yes)
			(layer "F.SilkS")
			(effects
				(font
					(size 0.7874 0.5842)
					(thickness 0.1524)
				)
				(justify left)
			)
		)
		(property "Value" ""
			(at 0 0 90)
			(layer "F.Fab")
			(effects
				(font
					(size 1.27 1.27)
				)
			)
		)
		(duplicate_pad_numbers_are_jumpers no)
		(fp_line
			(start 4.107942 -1.459992)
			(end 4.107942 1.459992)
			(stroke
				(width 0.1524)
				(type default)
			)
			(layer "F.SilkS")
		)
		(fp_line
			(start -3.400044 -1.459992)
			(end 4.107942 -1.459992)
			(stroke
				(width 0.1524)
				(type default)
			)
			(layer "F.SilkS")
		)
		(fp_line
			(start 4.107942 1.459992)
			(end -3.400044 1.459992)
			(stroke
				(width 0.1524)
				(type default)
			)
			(layer "F.SilkS")
		)
		(fp_line
			(start -3.400044 1.459992)
			(end -3.400044 -1.459992)
			(stroke
				(width 0.1524)
				(type default)
			)
			(layer "F.SilkS")
		)
		(fp_poly
			(pts
				(xy 4.107942 -1.459992) (xy 4.107942 1.459992) (xy 3.308096 1.459992) (xy 3.308096 -1.459992)
			)
			(stroke
				(width 0)
				(type default)
			)
			(fill yes)
			(layer "F.SilkS")
		)
		(fp_line
			(start 2.29997 -1.459992)
			(end 2.29997 1.459992)
			(stroke
				(width 0.1)
				(type default)
			)
			(layer "F.Fab")
		)
		(fp_line
			(start -2.29997 -1.459992)
			(end 2.29997 -1.459992)
			(stroke
				(width 0.1)
				(type default)
			)
			(layer "F.Fab")
		)
		(fp_line
			(start 2.29997 1.459992)
			(end -2.29997 1.459992)
			(stroke
				(width 0.1)
				(type default)
			)
			(layer "F.Fab")
		)
		(fp_line
			(start -2.29997 1.459992)
			(end -2.29997 -1.459992)
			(stroke
				(width 0.1)
				(type default)
			)
			(layer "F.Fab")
		)
		(fp_text user "-"
			(at 3.98272 -2.073148 270)
			(unlocked yes)
			(layer "F.SilkS")
			(effects
				(font
					(size 1.905 1.4224)
					(thickness 0.1524)
				)
				(justify left)
			)
		)
		(fp_text user "+"
			(at -4.7752 -0.12065 90)
			(unlocked yes)
			(layer "F.SilkS")
			(effects
				(font
					(size 1.905 1.4224)
					(thickness 0.1524)
				)
				(justify left)
			)
		)
		(fp_text user "+"
			(at -4.7752 -0.12065 90)
			(unlocked yes)
			(layer "F.Fab")
			(effects
				(font
					(size 1.905 1.4224)
					(thickness 0.1524)
				)
				(justify left)
			)
		)
		(fp_text user "-"
			(at 5.4102 0.29845 270)
			(unlocked yes)
			(layer "F.Fab")
			(effects
				(font
					(size 1.905 1.4224)
					(thickness 0.1524)
				)
				(justify left)
			)
		)
		(pad "A" smd rect
			(at -1.999996 0 180)
			(size 1.7018 2.5146)
			(layers "F.Cu" "F.Mask" "F.Paste")
			(net "GND")
		)
		(pad "C" smd rect
			(at 1.999996 0 180)
			(size 1.7018 2.5146)
			(layers "F.Cu" "F.Mask" "F.Paste")
			(net "P12V_NIC0_R")
		)
	)
)
